(kicad_pcb
	(version 20260206)
	(generator "pcbnew")
	(generator_version "10.0")
	(general
		(thickness 1.6)
		(legacy_teardrops no)
	)
	(paper "A4")
	(title_block
		(title "v1-chassis-manager — T6M_CM_d_v01_1031_1645.brd")
		(comment 1 "Open CloudServer (Microsoft) / footprint 1045 of 2512 (J2), pads 1-119 of 208")
	)
	(layers
		(0 "F.Cu" signal "TOP")
		(4 "In1.Cu" signal "GND1")
		(6 "In2.Cu" signal "IN1")
		(8 "In3.Cu" signal "VCC1")
		(10 "In4.Cu" signal "VCC2")
		(12 "In5.Cu" signal "GND2")
		(14 "In6.Cu" signal "IN2")
		(16 "In7.Cu" signal "IN3")
		(18 "In8.Cu" signal "GND3")
		(2 "B.Cu" signal "BOTTOM")
		(9 "F.Adhes" user "F.Adhesive")
		(11 "B.Adhes" user "B.Adhesive")
		(13 "F.Paste" user "Package Geometry/Pastemask Top")
		(15 "B.Paste" user "Package Geometry/Pastemask Bottom")
		(5 "F.SilkS" user "Ref Des/Silkscreen Top")
		(7 "B.SilkS" user "Ref Des/Silkscreen Bottom")
		(1 "F.Mask" user "Board Geometry/Soldermask Top")
		(3 "B.Mask" user "Board Geometry/Soldermask Bottom")
		(17 "Dwgs.User" user "User.Drawings")
		(19 "Cmts.User" user "User.Comments")
		(21 "Eco1.User" user "User.Eco1")
		(23 "Eco2.User" user "User.Eco2")
		(25 "Edge.Cuts" user "Board Geometry/Outline")
		(27 "Margin" user)
		(31 "F.CrtYd" user "Package Geometry/Place Bound Top")
		(29 "B.CrtYd" user "Package Geometry/Place Bound Bottom")
		(35 "F.Fab" user "Ref Des/Assembly Top")
		(33 "B.Fab" user "Ref Des/Assembly Bottom")
	)
	(footprint ""
		(layer "F.Cu")
		(at 40.350186 -20.94992 90)
		(property "Reference" "J2"
			(at -2.420874 10.237724 0)
			(unlocked yes)
			(layer "F.SilkS")
			(effects
				(font
					(size 0.7874 0.5842)
					(thickness 0.1524)
				)
				(justify left)
			)
		)
		(property "Value" ""
			(at 0 0 90)
			(layer "F.Fab")
			(effects
				(font
					(size 1.27 1.27)
				)
			)
		)
		(duplicate_pad_numbers_are_jumpers no)
		(pad "" np_thru_hole circle
			(at 4.100068 -1.75006 90)
			(size 1.651 1.651)
			(drill 1.651)
			(layers "*.Cu" "*.Mask")
			(clearance 0.381)
			(thermal_gap 0.381)
		)
		(pad "" np_thru_hole circle
			(at 4.100068 65.049908 90)
			(size 1.1684 1.1684)
			(drill 1.1684)
			(layers "*.Cu" "*.Mask")
			(clearance 0.381)
			(thermal_gap 0.381)
		)
		(pad "1" smd rect
			(at 0 0)
			(size 0.381 2.0574)
			(layers "F.Cu" "F.Mask" "F.Paste")
			(net "P1V5_NODE1_DDR3_VREF0_D")
		)
		(pad "2" smd rect
			(at 8.199882 0.299974)
			(size 0.381 2.0574)
			(layers "F.Cu" "F.Mask" "F.Paste")
			(net "GND")
		)
		(pad "3" smd rect
			(at 0 0.599948)
			(size 0.381 2.0574)
			(layers "F.Cu" "F.Mask" "F.Paste")
			(net "GND")
		)
		(pad "4" smd rect
			(at 8.199882 0.899922)
			(size 0.381 2.0574)
			(layers "F.Cu" "F.Mask" "F.Paste")
			(net "M1_DQ_NODE1_DQ4")
		)
		(pad "5" smd rect
			(at 0 1.199896)
			(size 0.381 2.0574)
			(layers "F.Cu" "F.Mask" "F.Paste")
			(net "M1_DQ_NODE1_DQ0")
		)
		(pad "6" smd rect
			(at 8.199882 1.500124)
			(size 0.381 2.0574)
			(layers "F.Cu" "F.Mask" "F.Paste")
			(net "M1_DQ_NODE1_DQ5")
		)
		(pad "7" smd rect
			(at 0 1.800098)
			(size 0.381 2.0574)
			(layers "F.Cu" "F.Mask" "F.Paste")
			(net "M1_DQ_NODE1_DQ1")
		)
		(pad "8" smd rect
			(at 8.199882 2.100072)
			(size 0.381 2.0574)
			(layers "F.Cu" "F.Mask" "F.Paste")
			(net "GND")
		)
		(pad "9" smd rect
			(at 0 2.400046)
			(size 0.381 2.0574)
			(layers "F.Cu" "F.Mask" "F.Paste")
			(net "GND")
		)
		(pad "10" smd rect
			(at 8.199882 2.70002)
			(size 0.381 2.0574)
			(layers "F.Cu" "F.Mask" "F.Paste")
			(net "M_DDR3_NODE1_DQS0N")
		)
		(pad "11" smd rect
			(at 0 2.999994)
			(size 0.381 2.0574)
			(layers "F.Cu" "F.Mask" "F.Paste")
			(net "PD_NODE1_DM0")
		)
		(pad "12" smd rect
			(at 8.199882 3.299968)
			(size 0.381 2.0574)
			(layers "F.Cu" "F.Mask" "F.Paste")
			(net "M_DDR3_NODE1_DQS0P")
		)
		(pad "13" smd rect
			(at 0 3.599942)
			(size 0.381 2.0574)
			(layers "F.Cu" "F.Mask" "F.Paste")
			(net "M1_DQ_NODE1_DQ2")
		)
		(pad "14" smd rect
			(at 8.199882 3.899916)
			(size 0.381 2.0574)
			(layers "F.Cu" "F.Mask" "F.Paste")
			(net "GND")
		)
		(pad "15" smd rect
			(at 0 4.19989)
			(size 0.381 2.0574)
			(layers "F.Cu" "F.Mask" "F.Paste")
			(net "M1_DQ_NODE1_DQ3")
		)
		(pad "16" smd rect
			(at 8.199882 4.500118)
			(size 0.381 2.0574)
			(layers "F.Cu" "F.Mask" "F.Paste")
			(net "M1_DQ_NODE1_DQ6")
		)
		(pad "17" smd rect
			(at 0 4.800092)
			(size 0.381 2.0574)
			(layers "F.Cu" "F.Mask" "F.Paste")
			(net "GND")
		)
		(pad "18" smd rect
			(at 8.199882 5.100066)
			(size 0.381 2.0574)
			(layers "F.Cu" "F.Mask" "F.Paste")
			(net "M1_DQ_NODE1_DQ7")
		)
		(pad "19" smd rect
			(at 0 5.40004)
			(size 0.381 2.0574)
			(layers "F.Cu" "F.Mask" "F.Paste")
			(net "M1_DQ_NODE1_DQ8")
		)
		(pad "20" smd rect
			(at 8.199882 5.700014)
			(size 0.381 2.0574)
			(layers "F.Cu" "F.Mask" "F.Paste")
			(net "GND")
		)
		(pad "21" smd rect
			(at 0 5.999988)
			(size 0.381 2.0574)
			(layers "F.Cu" "F.Mask" "F.Paste")
			(net "M1_DQ_NODE1_DQ9")
		)
		(pad "22" smd rect
			(at 8.199882 6.299962)
			(size 0.381 2.0574)
			(layers "F.Cu" "F.Mask" "F.Paste")
			(net "M1_DQ_NODE1_DQ12")
		)
		(pad "23" smd rect
			(at 0 6.599936)
			(size 0.381 2.0574)
			(layers "F.Cu" "F.Mask" "F.Paste")
			(net "GND")
		)
		(pad "24" smd rect
			(at 8.199882 6.89991)
			(size 0.381 2.0574)
			(layers "F.Cu" "F.Mask" "F.Paste")
			(net "M1_DQ_NODE1_DQ13")
		)
		(pad "25" smd rect
			(at 0 7.199884)
			(size 0.381 2.0574)
			(layers "F.Cu" "F.Mask" "F.Paste")
			(net "M_DDR3_NODE1_DQS1N")
		)
		(pad "26" smd rect
			(at 8.199882 7.500112)
			(size 0.381 2.0574)
			(layers "F.Cu" "F.Mask" "F.Paste")
			(net "GND")
		)
		(pad "27" smd rect
			(at 0 7.800086)
			(size 0.381 2.0574)
			(layers "F.Cu" "F.Mask" "F.Paste")
			(net "M_DDR3_NODE1_DQS1P")
		)
		(pad "28" smd rect
			(at 8.199882 8.10006)
			(size 0.381 2.0574)
			(layers "F.Cu" "F.Mask" "F.Paste")
			(net "PD_NODE1_DM1")
		)
		(pad "29" smd rect
			(at 0 8.400034)
			(size 0.381 2.0574)
			(layers "F.Cu" "F.Mask" "F.Paste")
			(net "GND")
		)
		(pad "30" smd rect
			(at 8.199882 8.700008)
			(size 0.381 2.0574)
			(layers "F.Cu" "F.Mask" "F.Paste")
			(net "M_NODE1_DIMM_RST_L")
		)
		(pad "31" smd rect
			(at 0 8.999982)
			(size 0.381 2.0574)
			(layers "F.Cu" "F.Mask" "F.Paste")
			(net "M1_DQ_NODE1_DQ10")
		)
		(pad "32" smd rect
			(at 8.199882 9.299956)
			(size 0.381 2.0574)
			(layers "F.Cu" "F.Mask" "F.Paste")
			(net "GND")
		)
		(pad "33" smd rect
			(at 0 9.59993)
			(size 0.381 2.0574)
			(layers "F.Cu" "F.Mask" "F.Paste")
			(net "M1_DQ_NODE1_DQ11")
		)
		(pad "34" smd rect
			(at 8.199882 9.899904)
			(size 0.381 2.0574)
			(layers "F.Cu" "F.Mask" "F.Paste")
			(net "M1_DQ_NODE1_DQ14")
		)
		(pad "35" smd rect
			(at 0 10.199878)
			(size 0.381 2.0574)
			(layers "F.Cu" "F.Mask" "F.Paste")
			(net "GND")
		)
		(pad "36" smd rect
			(at 8.199882 10.500106)
			(size 0.381 2.0574)
			(layers "F.Cu" "F.Mask" "F.Paste")
			(net "M1_DQ_NODE1_DQ15")
		)
		(pad "37" smd rect
			(at 0 10.80008)
			(size 0.381 2.0574)
			(layers "F.Cu" "F.Mask" "F.Paste")
			(net "M1_DQ_NODE1_DQ16")
		)
		(pad "38" smd rect
			(at 8.199882 11.100054)
			(size 0.381 2.0574)
			(layers "F.Cu" "F.Mask" "F.Paste")
			(net "GND")
		)
		(pad "39" smd rect
			(at 0 11.400028)
			(size 0.381 2.0574)
			(layers "F.Cu" "F.Mask" "F.Paste")
			(net "M1_DQ_NODE1_DQ17")
		)
		(pad "40" smd rect
			(at 8.199882 11.700002)
			(size 0.381 2.0574)
			(layers "F.Cu" "F.Mask" "F.Paste")
			(net "M1_DQ_NODE1_DQ20")
		)
		(pad "41" smd rect
			(at 0 11.999976)
			(size 0.381 2.0574)
			(layers "F.Cu" "F.Mask" "F.Paste")
			(net "GND")
		)
		(pad "42" smd rect
			(at 8.199882 12.29995)
			(size 0.381 2.0574)
			(layers "F.Cu" "F.Mask" "F.Paste")
			(net "M1_DQ_NODE1_DQ21")
		)
		(pad "43" smd rect
			(at 0 12.599924)
			(size 0.381 2.0574)
			(layers "F.Cu" "F.Mask" "F.Paste")
			(net "M_DDR3_NODE1_DQS2N")
		)
		(pad "44" smd rect
			(at 8.199882 12.899898)
			(size 0.381 2.0574)
			(layers "F.Cu" "F.Mask" "F.Paste")
			(net "PD_NODE1_DM2")
		)
		(pad "45" smd rect
			(at 0 13.199872)
			(size 0.381 2.0574)
			(layers "F.Cu" "F.Mask" "F.Paste")
			(net "M_DDR3_NODE1_DQS2P")
		)
		(pad "46" smd rect
			(at 8.199882 13.5001)
			(size 0.381 2.0574)
			(layers "F.Cu" "F.Mask" "F.Paste")
			(net "GND")
		)
		(pad "47" smd rect
			(at 0 13.800074)
			(size 0.381 2.0574)
			(layers "F.Cu" "F.Mask" "F.Paste")
			(net "GND")
		)
		(pad "48" smd rect
			(at 8.199882 14.100048)
			(size 0.381 2.0574)
			(layers "F.Cu" "F.Mask" "F.Paste")
			(net "M1_DQ_NODE1_DQ22")
		)
		(pad "49" smd rect
			(at 0 14.400022)
			(size 0.381 2.0574)
			(layers "F.Cu" "F.Mask" "F.Paste")
			(net "M1_DQ_NODE1_DQ18")
		)
		(pad "50" smd rect
			(at 8.199882 14.699996)
			(size 0.381 2.0574)
			(layers "F.Cu" "F.Mask" "F.Paste")
			(net "M1_DQ_NODE1_DQ23")
		)
		(pad "51" smd rect
			(at 0 14.99997)
			(size 0.381 2.0574)
			(layers "F.Cu" "F.Mask" "F.Paste")
			(net "M1_DQ_NODE1_DQ19")
		)
		(pad "52" smd rect
			(at 8.199882 15.299944)
			(size 0.381 2.0574)
			(layers "F.Cu" "F.Mask" "F.Paste")
			(net "GND")
		)
		(pad "53" smd rect
			(at 0 15.599918)
			(size 0.381 2.0574)
			(layers "F.Cu" "F.Mask" "F.Paste")
			(net "GND")
		)
		(pad "54" smd rect
			(at 8.199882 15.899892)
			(size 0.381 2.0574)
			(layers "F.Cu" "F.Mask" "F.Paste")
			(net "M1_DQ_NODE1_DQ28")
		)
		(pad "55" smd rect
			(at 0 16.20012)
			(size 0.381 2.0574)
			(layers "F.Cu" "F.Mask" "F.Paste")
			(net "M1_DQ_NODE1_DQ24")
		)
		(pad "56" smd rect
			(at 8.199882 16.500094)
			(size 0.381 2.0574)
			(layers "F.Cu" "F.Mask" "F.Paste")
			(net "M1_DQ_NODE1_DQ29")
		)
		(pad "57" smd rect
			(at 0 16.800068)
			(size 0.381 2.0574)
			(layers "F.Cu" "F.Mask" "F.Paste")
			(net "M1_DQ_NODE1_DQ25")
		)
		(pad "58" smd rect
			(at 8.199882 17.100042)
			(size 0.381 2.0574)
			(layers "F.Cu" "F.Mask" "F.Paste")
			(net "GND")
		)
		(pad "59" smd rect
			(at 0 17.400016)
			(size 0.381 2.0574)
			(layers "F.Cu" "F.Mask" "F.Paste")
			(net "PD_NODE1_DM3")
		)
		(pad "60" smd rect
			(at 8.199882 17.69999)
			(size 0.381 2.0574)
			(layers "F.Cu" "F.Mask" "F.Paste")
			(net "M_DDR3_NODE1_DQS3N")
		)
		(pad "61" smd rect
			(at 0 17.999964)
			(size 0.381 2.0574)
			(layers "F.Cu" "F.Mask" "F.Paste")
			(net "GND")
		)
		(pad "62" smd rect
			(at 8.199882 18.299938)
			(size 0.381 2.0574)
			(layers "F.Cu" "F.Mask" "F.Paste")
			(net "M_DDR3_NODE1_DQS3P")
		)
		(pad "63" smd rect
			(at 0 18.599912)
			(size 0.381 2.0574)
			(layers "F.Cu" "F.Mask" "F.Paste")
			(net "M1_DQ_NODE1_DQ26")
		)
		(pad "64" smd rect
			(at 8.199882 18.899886)
			(size 0.381 2.0574)
			(layers "F.Cu" "F.Mask" "F.Paste")
			(net "GND")
		)
		(pad "65" smd rect
			(at 0 19.200114)
			(size 0.381 2.0574)
			(layers "F.Cu" "F.Mask" "F.Paste")
			(net "M1_DQ_NODE1_DQ27")
		)
		(pad "66" smd rect
			(at 8.199882 19.500088)
			(size 0.381 2.0574)
			(layers "F.Cu" "F.Mask" "F.Paste")
			(net "M1_DQ_NODE1_DQ30")
		)
		(pad "67" smd rect
			(at 0 19.800062)
			(size 0.381 2.0574)
			(layers "F.Cu" "F.Mask" "F.Paste")
			(net "GND")
		)
		(pad "68" smd rect
			(at 8.199882 20.100036)
			(size 0.381 2.0574)
			(layers "F.Cu" "F.Mask" "F.Paste")
			(net "M1_DQ_NODE1_DQ31")
		)
		(pad "69" smd rect
			(at 0 20.40001)
			(size 0.381 2.0574)
			(layers "F.Cu" "F.Mask" "F.Paste")
			(net "M_DDR3_NODE1_ECC0")
		)
		(pad "70" smd rect
			(at 8.199882 20.699984)
			(size 0.381 2.0574)
			(layers "F.Cu" "F.Mask" "F.Paste")
			(net "GND")
		)
		(pad "71" smd rect
			(at 0 20.999958)
			(size 0.381 2.0574)
			(layers "F.Cu" "F.Mask" "F.Paste")
			(net "M_DDR3_NODE1_ECC1")
		)
		(pad "72" smd rect
			(at 8.199882 21.299932)
			(size 0.381 2.0574)
			(layers "F.Cu" "F.Mask" "F.Paste")
			(net "M_DDR3_NODE1_ECC4")
		)
		(pad "73" smd rect
			(at 0 23.999952)
			(size 0.381 2.0574)
			(layers "F.Cu" "F.Mask" "F.Paste")
			(net "GND")
		)
		(pad "74" smd rect
			(at 8.199882 24.299926)
			(size 0.381 2.0574)
			(layers "F.Cu" "F.Mask" "F.Paste")
			(net "M_DDR3_NODE1_ECC5")
		)
		(pad "75" smd rect
			(at 0 24.5999)
			(size 0.381 2.0574)
			(layers "F.Cu" "F.Mask" "F.Paste")
			(net "M_DDR3_NODE1_DQSECCN")
		)
		(pad "76" smd rect
			(at 8.199882 24.900128)
			(size 0.381 2.0574)
			(layers "F.Cu" "F.Mask" "F.Paste")
			(net "PD_NODE1_DM8")
		)
		(pad "77" smd rect
			(at 0 25.200102)
			(size 0.381 2.0574)
			(layers "F.Cu" "F.Mask" "F.Paste")
			(net "M_DDR3_NODE1_DQSECCP")
		)
		(pad "78" smd rect
			(at 8.199882 25.500076)
			(size 0.381 2.0574)
			(layers "F.Cu" "F.Mask" "F.Paste")
			(net "GND")
		)
		(pad "79" smd rect
			(at 0 25.80005)
			(size 0.381 2.0574)
			(layers "F.Cu" "F.Mask" "F.Paste")
			(net "GND")
		)
		(pad "80" smd rect
			(at 8.199882 26.100024)
			(size 0.381 2.0574)
			(layers "F.Cu" "F.Mask" "F.Paste")
			(net "M_DDR3_NODE1_ECC6")
		)
		(pad "81" smd rect
			(at 0 26.399998)
			(size 0.381 2.0574)
			(layers "F.Cu" "F.Mask" "F.Paste")
			(net "M_DDR3_NODE1_ECC2")
		)
		(pad "82" smd rect
			(at 8.199882 26.699972)
			(size 0.381 2.0574)
			(layers "F.Cu" "F.Mask" "F.Paste")
			(net "M_DDR3_NODE1_ECC7")
		)
		(pad "83" smd rect
			(at 0 26.999946)
			(size 0.381 2.0574)
			(layers "F.Cu" "F.Mask" "F.Paste")
			(net "M_DDR3_NODE1_ECC3")
		)
		(pad "84" smd rect
			(at 8.199882 27.29992)
			(size 0.381 2.0574)
			(layers "F.Cu" "F.Mask" "F.Paste")
			(net "P1V5_NODE1_DDR3_VREF_A_A")
		)
		(pad "85" smd rect
			(at 0 27.599894)
			(size 0.381 2.0574)
			(layers "F.Cu" "F.Mask" "F.Paste")
			(net "PV_VDDR_NODE1")
		)
		(pad "86" smd rect
			(at 8.199882 27.900122)
			(size 0.381 2.0574)
			(layers "F.Cu" "F.Mask" "F.Paste")
			(net "PV_VDDR_NODE1")
		)
		(pad "87" smd rect
			(at 0 28.200096)
			(size 0.381 2.0574)
			(layers "F.Cu" "F.Mask" "F.Paste")
			(net "M_DDR3_NODE1_CKE0")
		)
		(pad "88" smd rect
			(at 8.199882 28.50007)
			(size 0.381 2.0574)
			(layers "F.Cu" "F.Mask" "F.Paste")
			(net "M_DDR3_NODE1_MA15")
		)
		(pad "89" smd rect
			(at 0 28.800044)
			(size 0.381 2.0574)
			(layers "F.Cu" "F.Mask" "F.Paste")
			(net "M_DDR3_NODE1_CKE1")
		)
		(pad "90" smd rect
			(at 8.199882 29.100018)
			(size 0.381 2.0574)
			(layers "F.Cu" "F.Mask" "F.Paste")
			(net "M_DDR3_NODE1_MA14")
		)
		(pad "91" smd rect
			(at 0 29.399992)
			(size 0.381 2.0574)
			(layers "F.Cu" "F.Mask" "F.Paste")
			(net "M_DDR3_NODE1_BS2")
		)
		(pad "92" smd rect
			(at 8.199882 29.699966)
			(size 0.381 2.0574)
			(layers "F.Cu" "F.Mask" "F.Paste")
			(net "M_DDR3_NODE1_MA9")
		)
		(pad "93" smd rect
			(at 0 29.99994)
			(size 0.381 2.0574)
			(layers "F.Cu" "F.Mask" "F.Paste")
			(net "PV_VDDR_NODE1")
		)
		(pad "94" smd rect
			(at 8.199882 30.299914)
			(size 0.381 2.0574)
			(layers "F.Cu" "F.Mask" "F.Paste")
			(net "PV_VDDR_NODE1")
		)
		(pad "95" smd rect
			(at 0 30.599888)
			(size 0.381 2.0574)
			(layers "F.Cu" "F.Mask" "F.Paste")
			(net "M_DDR3_NODE1_MA12")
		)
		(pad "96" smd rect
			(at 8.199882 30.900116)
			(size 0.381 2.0574)
			(layers "F.Cu" "F.Mask" "F.Paste")
			(net "M_DDR3_NODE1_MA11")
		)
		(pad "97" smd rect
			(at 0 31.20009)
			(size 0.381 2.0574)
			(layers "F.Cu" "F.Mask" "F.Paste")
			(net "M_DDR3_NODE1_MA8")
		)
		(pad "98" smd rect
			(at 8.199882 31.500064)
			(size 0.381 2.0574)
			(layers "F.Cu" "F.Mask" "F.Paste")
			(net "M_DDR3_NODE1_MA7")
		)
		(pad "99" smd rect
			(at 0 31.800038)
			(size 0.381 2.0574)
			(layers "F.Cu" "F.Mask" "F.Paste")
			(net "M_DDR3_NODE1_MA5")
		)
		(pad "100" smd rect
			(at 8.199882 32.100012)
			(size 0.381 2.0574)
			(layers "F.Cu" "F.Mask" "F.Paste")
			(net "M_DDR3_NODE1_MA6")
		)
		(pad "101" smd rect
			(at 0 32.399986)
			(size 0.381 2.0574)
			(layers "F.Cu" "F.Mask" "F.Paste")
			(net "PV_VDDR_NODE1")
		)
		(pad "102" smd rect
			(at 8.199882 32.69996)
			(size 0.381 2.0574)
			(layers "F.Cu" "F.Mask" "F.Paste")
			(net "PV_VDDR_NODE1")
		)
		(pad "103" smd rect
			(at 0 32.999934)
			(size 0.381 2.0574)
			(layers "F.Cu" "F.Mask" "F.Paste")
			(net "M_DDR3_NODE1_MA3")
		)
		(pad "104" smd rect
			(at 8.199882 33.299908)
			(size 0.381 2.0574)
			(layers "F.Cu" "F.Mask" "F.Paste")
			(net "M_DDR3_NODE1_MA4")
		)
		(pad "105" smd rect
			(at 0 33.599882)
			(size 0.381 2.0574)
			(layers "F.Cu" "F.Mask" "F.Paste")
			(net "M_DDR3_NODE1_MA1")
		)
		(pad "106" smd rect
			(at 8.199882 33.90011)
			(size 0.381 2.0574)
			(layers "F.Cu" "F.Mask" "F.Paste")
			(net "M_DDR3_NODE1_MA2")
		)
		(pad "107" smd rect
			(at 0 34.200084)
			(size 0.381 2.0574)
			(layers "F.Cu" "F.Mask" "F.Paste")
			(net "M_DDR3_NODE1_MA0")
		)
		(pad "108" smd rect
			(at 8.199882 34.500058)
			(size 0.381 2.0574)
			(layers "F.Cu" "F.Mask" "F.Paste")
			(net "M_DDR3_NODE1_BS1")
		)
		(pad "109" smd rect
			(at 0 34.800032)
			(size 0.381 2.0574)
			(layers "F.Cu" "F.Mask" "F.Paste")
			(net "PV_VDDR_NODE1")
		)
		(pad "110" smd rect
			(at 8.199882 35.100006)
			(size 0.381 2.0574)
			(layers "F.Cu" "F.Mask" "F.Paste")
			(net "PV_VDDR_NODE1")
		)
		(pad "111" smd rect
			(at 0 35.39998)
			(size 0.381 2.0574)
			(layers "F.Cu" "F.Mask" "F.Paste")
			(net "M_DDR3_NODE1_CK0P")
		)
		(pad "112" smd rect
			(at 8.199882 35.699954)
			(size 0.381 2.0574)
			(layers "F.Cu" "F.Mask" "F.Paste")
			(net "M_DDR3_NODE1_CK1P")
		)
		(pad "113" smd rect
			(at 0 35.999928)
			(size 0.381 2.0574)
			(layers "F.Cu" "F.Mask" "F.Paste")
			(net "M_DDR3_NODE1_CK0N")
		)
		(pad "114" smd rect
			(at 8.199882 36.299902)
			(size 0.381 2.0574)
			(layers "F.Cu" "F.Mask" "F.Paste")
			(net "M_DDR3_NODE1_CK1N")
		)
		(pad "115" smd rect
			(at 0 36.599876)
			(size 0.381 2.0574)
			(layers "F.Cu" "F.Mask" "F.Paste")
			(net "PV_VDDR_NODE1")
		)
		(pad "116" smd rect
			(at 8.199882 36.900104)
			(size 0.381 2.0574)
			(layers "F.Cu" "F.Mask" "F.Paste")
			(net "PV_VDDR_NODE1")
		)
		(pad "117" smd rect
			(at 0 37.200078)
			(size 0.381 2.0574)
			(layers "F.Cu" "F.Mask" "F.Paste")
			(net "M_DDR3_NODE1_MA10")
		)
	)
)
